# BASEBOARD_FAB2 (Tioga Pass) — schematic netlist excerpt (pin names and nets, part order shuffled) for the footprints in the layout excerpt that follows; sources: Cadence DE-HDL packaged netlist, KiCad conversion of Wiwynn_Tioga_Pass_MB.brd

R8W3  RES  1.00K 1% CHIP  pkg 0402  page 235 : A = VR_PVNN_P1V05_PCH_VD12 ; B = PU_PVNN_PCH_VDIO
C4F6  CAPP  470UF 16V 20% ALUM  pkg 4040LF  page 195 : A = P12V_STBY ; B = GND

(kicad_pcb
	(version 20260206)
	(generator "pcbnew")
	(generator_version "10.0")
	(general
		(thickness 1.6)
		(legacy_teardrops no)
	)
	(paper "A4")
	(title_block
		(title "Wiwynn_Tioga_Pass_MB.brd")
		(comment 1 "Tioga Pass / footprints 214-215 of 4770")
	)
	(layers
		(0 "F.Cu" signal "TOP")
		(4 "In1.Cu" signal "L2GND")
		(6 "In2.Cu" signal "L3")
		(8 "In3.Cu" signal "L4GND")
		(10 "In4.Cu" signal "L5")
		(12 "In5.Cu" signal "L6GND")
		(14 "In6.Cu" signal "L7VCC")
		(16 "In7.Cu" signal "L8VCC")
		(18 "In8.Cu" signal "L9GND")
		(20 "In9.Cu" signal "L10")
		(22 "In10.Cu" signal "L11GND")
		(24 "In11.Cu" signal "L12")
		(26 "In12.Cu" signal "L13GND")
		(2 "B.Cu" signal "BOTTOM")
		(9 "F.Adhes" user "F.Adhesive")
		(11 "B.Adhes" user "B.Adhesive")
		(13 "F.Paste" user "Package Geometry/Pastemask Top")
		(15 "B.Paste" user "Package Geometry/Pastemask Bottom")
		(5 "F.SilkS" user "Ref Des/Silkscreen Top")
		(7 "B.SilkS" user "Ref Des/Silkscreen Bottom")
		(1 "F.Mask" user "Board Geometry/Soldermask Top")
		(3 "B.Mask" user "Board Geometry/Soldermask Bottom")
		(17 "Dwgs.User" user "User.Drawings")
		(19 "Cmts.User" user "User.Comments")
		(21 "Eco1.User" user "User.Eco1")
		(23 "Eco2.User" user "User.Eco2")
		(25 "Edge.Cuts" user "Board Geometry/Outline")
		(27 "Margin" user)
		(31 "F.CrtYd" user "Package Geometry/Place Bound Top")
		(29 "B.CrtYd" user "Package Geometry/Place Bound Bottom")
		(35 "F.Fab" user "Ref Des/Assembly Top")
		(33 "B.Fab" user "Ref Des/Assembly Bottom")
	)
	(footprint ""
		(layer "F.Cu")
		(at 198.87946 -30.861 180)
		(property "Reference" "C4F6"
			(at 0.75946 -3.83667 0)
			(unlocked yes)
			(layer "F.SilkS")
			(effects
				(font
					(size 0.7874 0.5842)
					(thickness 0.1524)
				)
			)
		)
		(property "Value" ""
			(at 0 0 180)
			(layer "F.Fab")
			(effects
				(font
					(size 1.27 1.27)
				)
			)
		)
		(duplicate_pad_numbers_are_jumpers no)
		(fp_line
			(start 5.1435 9.271)
			(end 1.4097 9.271)
			(stroke
				(width 0.1524)
				(type default)
			)
			(layer "F.SilkS")
		)
		(fp_line
			(start 5.1435 -0.127)
			(end 5.1435 9.271)
			(stroke
				(width 0.1524)
				(type default)
			)
			(layer "F.SilkS")
		)
		(fp_line
			(start 4.3815 -1.016)
			(end 5.1435 -0.127)
			(stroke
				(width 0.1524)
				(type default)
			)
			(layer "F.SilkS")
		)
		(fp_line
			(start 1.8415 2.0955)
			(end 1.4097 2.0955)
			(stroke
				(width 0.1524)
				(type default)
			)
			(layer "F.SilkS")
		)
		(fp_line
			(start 1.8415 -1.016)
			(end 4.3815 -1.016)
			(stroke
				(width 0.1524)
				(type default)
			)
			(layer "F.SilkS")
		)
		(fp_line
			(start 1.8415 -2.0955)
			(end 1.8415 2.0955)
			(stroke
				(width 0.1524)
				(type default)
			)
			(layer "F.SilkS")
		)
		(fp_line
			(start 1.4097 -2.0955)
			(end 1.8415 -2.0955)
			(stroke
				(width 0.1524)
				(type default)
			)
			(layer "F.SilkS")
		)
		(fp_line
			(start -1.4097 9.271)
			(end -5.1435 9.271)
			(stroke
				(width 0.1524)
				(type default)
			)
			(layer "F.SilkS")
		)
		(fp_line
			(start -1.4097 -2.0955)
			(end -1.8415 -2.0955)
			(stroke
				(width 0.1524)
				(type default)
			)
			(layer "F.SilkS")
		)
		(fp_line
			(start -1.8415 2.0955)
			(end -1.4097 2.0955)
			(stroke
				(width 0.1524)
				(type default)
			)
			(layer "F.SilkS")
		)
		(fp_line
			(start -1.8415 -2.0955)
			(end -1.8415 2.0955)
			(stroke
				(width 0.1524)
				(type default)
			)
			(layer "F.SilkS")
		)
		(fp_line
			(start -4.3815 -1.016)
			(end -1.8415 -1.016)
			(stroke
				(width 0.1524)
				(type default)
			)
			(layer "F.SilkS")
		)
		(fp_line
			(start -5.1435 9.271)
			(end -5.1435 -0.127)
			(stroke
				(width 0.1524)
				(type default)
			)
			(layer "F.SilkS")
		)
		(fp_line
			(start -5.1435 -0.127)
			(end -4.3815 -1.016)
			(stroke
				(width 0.1524)
				(type default)
			)
			(layer "F.SilkS")
		)
		(fp_poly
			(pts
				(xy -5.14604 -0.12954) (xy -4.38404 -1.01346) (xy 4.37896 -1.016) (xy 5.1435 -0.12954) (xy 5.14096 9.271)
				(xy -5.14604 9.27354)
			)
			(stroke
				(width 0)
				(type default)
			)
			(fill no)
			(layer "F.CrtYd")
		)
		(fp_line
			(start 5.1435 9.271)
			(end -5.1435 9.271)
			(stroke
				(width 0.1)
				(type default)
			)
			(layer "F.Fab")
		)
		(fp_line
			(start 5.1435 -0.127)
			(end 5.1435 9.271)
			(stroke
				(width 0.1)
				(type default)
			)
			(layer "F.Fab")
		)
		(fp_line
			(start 4.3815 -1.016)
			(end 5.1435 -0.127)
			(stroke
				(width 0.1)
				(type default)
			)
			(layer "F.Fab")
		)
		(fp_line
			(start -4.3815 -1.016)
			(end 4.3815 -1.016)
			(stroke
				(width 0.1)
				(type default)
			)
			(layer "F.Fab")
		)
		(fp_line
			(start -5.1435 9.271)
			(end -5.1435 -0.127)
			(stroke
				(width 0.1)
				(type default)
			)
			(layer "F.Fab")
		)
		(fp_line
			(start -5.1435 -0.127)
			(end -4.3815 -1.016)
			(stroke
				(width 0.1)
				(type default)
			)
			(layer "F.Fab")
		)
		(fp_circle
			(center 0 4.1275)
			(end -4.9911 4.1275)
			(stroke
				(width 0.1)
				(type default)
			)
			(fill no)
			(layer "F.Fab")
		)
		(pad "1" smd rect
			(at 0 0 180)
			(size 1.905 4.191)
			(layers "F.Cu" "F.Mask" "F.Paste")
			(net "P12V_STBY")
		)
		(pad "2" smd rect
			(at 0 8.255 180)
			(size 1.905 4.191)
			(layers "F.Cu" "F.Mask" "F.Paste")
			(net "GND")
		)
		(zone
			(layer "F.Cu")
			(hatch none 0.5)
			(connect_pads
				(clearance 0)
			)
			(min_thickness 0.25)
			(keepout
				(tracks allowed)
				(vias not_allowed)
				(pads allowed)
				(copperpour not_allowed)
				(footprints allowed)
			)
			(placement
				(enabled no)
				(sheetname "")
			)
			(fill
				(thermal_gap 0.5)
				(thermal_bridge_width 0.5)
				(island_removal_mode 0)
			)
			(polygon
				(pts
					(xy 204.02296 -40.132) (xy 193.73596 -40.132) (xy 193.73596 -30.734) (xy 194.49796 -29.845) (xy 203.26096 -29.845)
					(xy 204.02296 -30.734)
				)
			)
		)
	)
	(footprint ""
		(layer "F.Cu")
		(at 399.67408 -155.08986)
		(property "Reference" "R8W3"
			(at -0.8382 -0.67818 0)
			(unlocked yes)
			(layer "F.SilkS")
			(effects
				(font
					(size 0.4064 0.254)
					(thickness 0.1524)
				)
				(justify left)
			)
		)
		(property "Value" ""
			(at 0 0 0)
			(layer "F.Fab")
			(effects
				(font
					(size 1.27 1.27)
				)
			)
		)
		(duplicate_pad_numbers_are_jumpers no)
		(fp_poly
			(pts
				(xy -0.2794 -0.1016) (xy 0.2794 -0.1016) (xy 0.2794 0.9906) (xy -0.2794 0.9906)
			)
			(stroke
				(width 0)
				(type default)
			)
			(fill no)
			(layer "F.CrtYd")
		)
		(fp_line
			(start -0.2794 -0.1016)
			(end -0.2794 0.9906)
			(stroke
				(width 0.1)
				(type default)
			)
			(layer "F.Fab")
		)
		(fp_line
			(start -0.2794 0.9906)
			(end 0.2794 0.9906)
			(stroke
				(width 0.1)
				(type default)
			)
			(layer "F.Fab")
		)
		(fp_line
			(start 0.2794 -0.1016)
			(end -0.2794 -0.1016)
			(stroke
				(width 0.1)
				(type default)
			)
			(layer "F.Fab")
		)
		(fp_line
			(start 0.2794 0.9906)
			(end 0.2794 -0.1016)
			(stroke
				(width 0.1)
				(type default)
			)
			(layer "F.Fab")
		)
		(pad "1" smd rect
			(at 0 0)
			(size 0.508 0.508)
			(layers "F.Cu" "F.Mask" "F.Paste")
			(net "VR_PVNN_P1V05_PCH_VD12")
		)
		(pad "2" smd rect
			(at 0 0.889)
			(size 0.508 0.508)
			(layers "F.Cu" "F.Mask" "F.Paste")
			(net "PU_PVNN_PCH_VDIO")
		)
		(zone
			(layer "F.Cu")
			(hatch none 0.5)
			(connect_pads
				(clearance 0)
			)
			(min_thickness 0.25)
			(keepout
				(tracks allowed)
				(vias not_allowed)
				(pads allowed)
				(copperpour not_allowed)
				(footprints allowed)
			)
			(placement
				(enabled no)
				(sheetname "")
			)
			(fill
				(thermal_gap 0.5)
				(thermal_bridge_width 0.5)
				(island_removal_mode 0)
			)
			(polygon
				(pts
					(xy 399.42008 -154.83586) (xy 399.92808 -154.83586) (xy 399.92808 -154.45486) (xy 399.42008 -154.45486)
				)
			)
		)
		(zone
			(layer "F.Cu")
			(hatch none 0.5)
			(connect_pads
				(clearance 0)
			)
			(min_thickness 0.25)
			(keepout
				(tracks not_allowed)
				(vias allowed)
				(pads allowed)
				(copperpour not_allowed)
				(footprints allowed)
			)
			(placement
				(enabled no)
				(sheetname "")
			)
			(fill
				(thermal_gap 0.5)
				(thermal_bridge_width 0.5)
				(island_removal_mode 0)
			)
			(polygon
				(pts
					(xy 399.42008 -154.45486) (xy 399.92808 -154.45486) (xy 399.92808 -154.83586) (xy 399.42008 -154.83586)
				)
			)
		)
	)
)
